(kicad_pcb
	(version 20260206)
	(generator "pcbnew")
	(generator_version "10.0")
	(general
		(thickness 1.6)
		(legacy_teardrops no)
	)
	(paper "A4")
	(title_block
		(title "Wiwynn_Tioga_Pass_MB.brd")
		(comment 1 "Tioga Pass / footprints 3216-3222 of 4770")
	)
	(layers
		(0 "F.Cu" signal "TOP")
		(4 "In1.Cu" signal "L2GND")
		(6 "In2.Cu" signal "L3")
		(8 "In3.Cu" signal "L4GND")
		(10 "In4.Cu" signal "L5")
		(12 "In5.Cu" signal "L6GND")
		(14 "In6.Cu" signal "L7VCC")
		(16 "In7.Cu" signal "L8VCC")
		(18 "In8.Cu" signal "L9GND")
		(20 "In9.Cu" signal "L10")
		(22 "In10.Cu" signal "L11GND")
		(24 "In11.Cu" signal "L12")
		(26 "In12.Cu" signal "L13GND")
		(2 "B.Cu" signal "BOTTOM")
		(9 "F.Adhes" user "F.Adhesive")
		(11 "B.Adhes" user "B.Adhesive")
		(13 "F.Paste" user "Package Geometry/Pastemask Top")
		(15 "B.Paste" user "Package Geometry/Pastemask Bottom")
		(5 "F.SilkS" user "Ref Des/Silkscreen Top")
		(7 "B.SilkS" user "Ref Des/Silkscreen Bottom")
		(1 "F.Mask" user "Board Geometry/Soldermask Top")
		(3 "B.Mask" user "Board Geometry/Soldermask Bottom")
		(17 "Dwgs.User" user "User.Drawings")
		(19 "Cmts.User" user "User.Comments")
		(21 "Eco1.User" user "User.Eco1")
		(23 "Eco2.User" user "User.Eco2")
		(25 "Edge.Cuts" user "Board Geometry/Outline")
		(27 "Margin" user)
		(31 "F.CrtYd" user "Package Geometry/Place Bound Top")
		(29 "B.CrtYd" user "Package Geometry/Place Bound Bottom")
		(35 "F.Fab" user "Ref Des/Assembly Top")
		(33 "B.Fab" user "Ref Des/Assembly Bottom")
	)
	(footprint ""
		(layer "B.Cu")
		(at 194.6402 -102.6668 180)
		(property "Reference" "R6N13"
			(at 0 0 0)
			(layer "B.SilkS")
			(hide yes)
			(effects
				(font
					(size 1.27 1.27)
				)
				(justify mirror)
			)
		)
		(property "Value" ""
			(at 0 0 0)
			(layer "B.Fab")
			(effects
				(font
					(size 1.27 1.27)
				)
				(justify mirror)
			)
		)
		(duplicate_pad_numbers_are_jumpers no)
		(fp_poly
			(pts
				(xy 0.2794 -0.1016) (xy -0.2794 -0.1016) (xy -0.2794 0.9906) (xy 0.2794 0.9906)
			)
			(stroke
				(width 0)
				(type default)
			)
			(fill no)
			(layer "B.CrtYd")
		)
		(fp_line
			(start 0.2794 0.9906)
			(end -0.2794 0.9906)
			(stroke
				(width 0.1)
				(type default)
			)
			(layer "B.Fab")
		)
		(fp_line
			(start 0.2794 -0.1016)
			(end 0.2794 0.9906)
			(stroke
				(width 0.1)
				(type default)
			)
			(layer "B.Fab")
		)
		(fp_line
			(start -0.2794 0.9906)
			(end -0.2794 -0.1016)
			(stroke
				(width 0.1)
				(type default)
			)
			(layer "B.Fab")
		)
		(fp_line
			(start -0.2794 -0.1016)
			(end 0.2794 -0.1016)
			(stroke
				(width 0.1)
				(type default)
			)
			(layer "B.Fab")
		)
		(pad "1" smd rect
			(at 0 0)
			(size 0.508 0.508)
			(layers "B.Cu" "B.Mask" "B.Paste")
			(net "GND")
		)
		(pad "2" smd rect
			(at 0 0.889)
			(size 0.508 0.508)
			(layers "B.Cu" "B.Mask" "B.Paste")
			(net "PD_PIROM_CPU0_ADDR1")
		)
		(zone
			(layer "B.Cu")
			(hatch none 0.5)
			(connect_pads
				(clearance 0)
			)
			(min_thickness 0.25)
			(keepout
				(tracks not_allowed)
				(vias allowed)
				(pads allowed)
				(copperpour not_allowed)
				(footprints allowed)
			)
			(placement
				(enabled no)
				(sheetname "")
			)
			(fill
				(thermal_gap 0.5)
				(thermal_bridge_width 0.5)
				(island_removal_mode 0)
			)
			(polygon
				(pts
					(xy 194.3862 -103.3018) (xy 194.8942 -103.3018) (xy 194.8942 -102.9208) (xy 194.3862 -102.9208)
				)
			)
		)
		(zone
			(layer "B.Cu")
			(hatch none 0.5)
			(connect_pads
				(clearance 0)
			)
			(min_thickness 0.25)
			(keepout
				(tracks allowed)
				(vias not_allowed)
				(pads allowed)
				(copperpour not_allowed)
				(footprints allowed)
			)
			(placement
				(enabled no)
				(sheetname "")
			)
			(fill
				(thermal_gap 0.5)
				(thermal_bridge_width 0.5)
				(island_removal_mode 0)
			)
			(polygon
				(pts
					(xy 194.3862 -102.9208) (xy 194.8942 -102.9208) (xy 194.8942 -103.3018) (xy 194.3862 -103.3018)
				)
			)
		)
	)
	(footprint ""
		(layer "B.Cu")
		(at 333.346806 -61.257434)
		(property "Reference" "C2U3"
			(at 0 0 0)
			(layer "B.SilkS")
			(hide yes)
			(effects
				(font
					(size 1.27 1.27)
				)
				(justify mirror)
			)
		)
		(property "Value" ""
			(at 0 0 0)
			(layer "B.Fab")
			(effects
				(font
					(size 1.27 1.27)
				)
				(justify mirror)
			)
		)
		(duplicate_pad_numbers_are_jumpers no)
		(fp_poly
			(pts
				(xy -0.3048 -0.1016) (xy -0.3048 0.9906) (xy 0.3048 0.9906) (xy 0.3048 -0.1016)
			)
			(stroke
				(width 0)
				(type default)
			)
			(fill no)
			(layer "B.CrtYd")
		)
		(fp_line
			(start -0.3048 -0.1016)
			(end 0.3048 -0.1016)
			(stroke
				(width 0.1)
				(type default)
			)
			(layer "B.Fab")
		)
		(fp_line
			(start -0.3048 0.9906)
			(end -0.3048 -0.1016)
			(stroke
				(width 0.1)
				(type default)
			)
			(layer "B.Fab")
		)
		(fp_line
			(start 0.3048 -0.1016)
			(end 0.3048 0.9906)
			(stroke
				(width 0.1)
				(type default)
			)
			(layer "B.Fab")
		)
		(fp_line
			(start 0.3048 0.9906)
			(end -0.3048 0.9906)
			(stroke
				(width 0.1)
				(type default)
			)
			(layer "B.Fab")
		)
		(pad "1" smd rect
			(at 0 0 180)
			(size 0.508 0.508)
			(layers "B.Cu" "B.Mask" "B.Paste")
			(net "P3E_CPU0_PE1_PCH_RXP<0>")
		)
		(pad "2" smd rect
			(at 0 0.889 180)
			(size 0.508 0.508)
			(layers "B.Cu" "B.Mask" "B.Paste")
			(net "P3E_CPU0_PE1_SS_RXP<0>")
		)
		(zone
			(layer "B.Cu")
			(hatch none 0.5)
			(connect_pads
				(clearance 0)
			)
			(min_thickness 0.25)
			(keepout
				(tracks allowed)
				(vias not_allowed)
				(pads allowed)
				(copperpour not_allowed)
				(footprints allowed)
			)
			(placement
				(enabled no)
				(sheetname "")
			)
			(fill
				(thermal_gap 0.5)
				(thermal_bridge_width 0.5)
				(island_removal_mode 0)
			)
			(polygon
				(pts
					(xy 333.600806 -61.003434) (xy 333.092806 -61.003434) (xy 333.092806 -60.622434) (xy 333.600806 -60.622434)
				)
			)
		)
		(zone
			(layer "B.Cu")
			(hatch none 0.5)
			(connect_pads
				(clearance 0)
			)
			(min_thickness 0.25)
			(keepout
				(tracks not_allowed)
				(vias allowed)
				(pads allowed)
				(copperpour not_allowed)
				(footprints allowed)
			)
			(placement
				(enabled no)
				(sheetname "")
			)
			(fill
				(thermal_gap 0.5)
				(thermal_bridge_width 0.5)
				(island_removal_mode 0)
			)
			(polygon
				(pts
					(xy 333.600806 -60.622434) (xy 333.092806 -60.622434) (xy 333.092806 -61.003434) (xy 333.600806 -61.003434)
				)
			)
		)
	)
	(footprint ""
		(layer "B.Cu")
		(at 410.679646 -25.790652 180)
		(property "Reference" "FB2T1"
			(at 0 0 0)
			(layer "B.SilkS")
			(hide yes)
			(effects
				(font
					(size 1.27 1.27)
				)
				(justify mirror)
			)
		)
		(property "Value" "*"
			(at -0.0254 -2.8829 180)
			(unlocked yes)
			(layer "B.Fab")
			(hide yes)
			(effects
				(font
					(size 1.27 1.016)
					(thickness 0.1524)
				)
				(justify mirror)
			)
		)
		(property "Device Type" "HCB1608KF-800T30-GP_DISCRET-G9A"
			(at -0.0254 -4.4069 180)
			(unlocked yes)
			(layer "B.Fab")
			(hide yes)
			(effects
				(font
					(size 1.27 1.016)
					(thickness 0.1524)
				)
				(justify mirror)
			)
		)
		(duplicate_pad_numbers_are_jumpers no)
		(fp_line
			(start -0.254 0)
			(end 0.254 0)
			(stroke
				(width 0.2032)
				(type default)
			)
			(layer "B.SilkS")
		)
		(fp_rect
			(start 0.5842 1.3335)
			(end -0.5842 -1.3335)
			(stroke
				(width 0)
				(type default)
			)
			(fill no)
			(layer "B.CrtYd")
		)
		(fp_rect
			(start 0.5842 1.3335)
			(end -0.5842 -1.3335)
			(stroke
				(width 0)
				(type default)
			)
			(fill no)
			(layer "B.Fab")
		)
		(pad "1" smd custom
			(at 0 -0.762)
			(size 0.2159 0.2159)
			(layers "B.Cu" "B.Mask" "B.Paste")
			(net "P3V3_STBY")
			(options
				(clearance outline)
				(anchor circle)
			)
			(primitives
				(gr_poly
					(pts
						(arc
							(start -0.3302 0.4318)
							(mid -0.402042 0.402042)
							(end -0.4318 0.3302)
						)
						(arc
							(start -0.4318 -0.3302)
							(mid -0.402042 -0.402042)
							(end -0.3302 -0.4318)
						)
						(arc
							(start 0.3302 -0.4318)
							(mid 0.402042 -0.402042)
							(end 0.4318 -0.3302)
						)
						(arc
							(start 0.4318 0.3302)
							(mid 0.402042 0.402042)
							(end 0.3302 0.4318)
						)
					)
					(width 0)
					(fill yes)
				)
			)
		)
		(pad "2" smd custom
			(at 0 0.762)
			(size 0.2159 0.2159)
			(layers "B.Cu" "B.Mask" "B.Paste")
			(net "VCC_VA_3V3")
			(options
				(clearance outline)
				(anchor circle)
			)
			(primitives
				(gr_poly
					(pts
						(arc
							(start -0.3302 0.4318)
							(mid -0.402042 0.402042)
							(end -0.4318 0.3302)
						)
						(arc
							(start -0.4318 -0.3302)
							(mid -0.402042 -0.402042)
							(end -0.3302 -0.4318)
						)
						(arc
							(start 0.3302 -0.4318)
							(mid 0.402042 -0.402042)
							(end 0.4318 -0.3302)
						)
						(arc
							(start 0.4318 0.3302)
							(mid 0.402042 0.402042)
							(end 0.3302 0.4318)
						)
					)
					(width 0)
					(fill yes)
				)
			)
		)
	)
	(footprint ""
		(layer "B.Cu")
		(at 355.349048 -86.312248 -90)
		(property "Reference" "C3P1"
			(at 0 0 90)
			(layer "B.SilkS")
			(hide yes)
			(effects
				(font
					(size 1.27 1.27)
				)
				(justify mirror)
			)
		)
		(property "Value" ""
			(at 0 0 90)
			(layer "B.Fab")
			(effects
				(font
					(size 1.27 1.27)
				)
				(justify mirror)
			)
		)
		(duplicate_pad_numbers_are_jumpers no)
		(fp_poly
			(pts
				(xy -0.3048 -0.1016) (xy -0.3048 0.9906) (xy 0.3048 0.9906) (xy 0.3048 -0.1016)
			)
			(stroke
				(width 0)
				(type default)
			)
			(fill no)
			(layer "B.CrtYd")
		)
		(fp_line
			(start -0.3048 0.9906)
			(end -0.3048 -0.1016)
			(stroke
				(width 0.1)
				(type default)
			)
			(layer "B.Fab")
		)
		(fp_line
			(start 0.3048 0.9906)
			(end -0.3048 0.9906)
			(stroke
				(width 0.1)
				(type default)
			)
			(layer "B.Fab")
		)
		(fp_line
			(start -0.3048 -0.1016)
			(end 0.3048 -0.1016)
			(stroke
				(width 0.1)
				(type default)
			)
			(layer "B.Fab")
		)
		(fp_line
			(start 0.3048 -0.1016)
			(end 0.3048 0.9906)
			(stroke
				(width 0.1)
				(type default)
			)
			(layer "B.Fab")
		)
		(pad "1" smd rect
			(at 0 0 90)
			(size 0.508 0.508)
			(layers "B.Cu" "B.Mask" "B.Paste")
			(net "VSENSE_PVCCIO_CPU0_SKT_VSEN")
		)
		(pad "2" smd rect
			(at 0 0.889 90)
			(size 0.508 0.508)
			(layers "B.Cu" "B.Mask" "B.Paste")
			(net "VSENSE_PVCCIO_CPU0_SKT_VRTN")
		)
		(zone
			(layer "B.Cu")
			(hatch none 0.5)
			(connect_pads
				(clearance 0)
			)
			(min_thickness 0.25)
			(keepout
				(tracks not_allowed)
				(vias allowed)
				(pads allowed)
				(copperpour not_allowed)
				(footprints allowed)
			)
			(placement
				(enabled no)
				(sheetname "")
			)
			(fill
				(thermal_gap 0.5)
				(thermal_bridge_width 0.5)
				(island_removal_mode 0)
			)
			(polygon
				(pts
					(xy 354.714048 -86.058248) (xy 354.714048 -86.566248) (xy 355.095048 -86.566248) (xy 355.095048 -86.058248)
				)
			)
		)
		(zone
			(layer "B.Cu")
			(hatch none 0.5)
			(connect_pads
				(clearance 0)
			)
			(min_thickness 0.25)
			(keepout
				(tracks allowed)
				(vias not_allowed)
				(pads allowed)
				(copperpour not_allowed)
				(footprints allowed)
			)
			(placement
				(enabled no)
				(sheetname "")
			)
			(fill
				(thermal_gap 0.5)
				(thermal_bridge_width 0.5)
				(island_removal_mode 0)
			)
			(polygon
				(pts
					(xy 355.095048 -86.058248) (xy 355.095048 -86.566248) (xy 354.714048 -86.566248) (xy 354.714048 -86.058248)
				)
			)
		)
	)
	(footprint ""
		(layer "B.Cu")
		(at 411.5308 -36.5506 90)
		(property "Reference" "C25W45"
			(at 0.8382 -0.67818 90)
			(unlocked yes)
			(layer "B.SilkS")
			(effects
				(font
					(size 0.4064 0.254)
					(thickness 0.1524)
				)
				(justify left mirror)
			)
		)
		(property "Value" ""
			(at 0 0 90)
			(layer "B.Fab")
			(effects
				(font
					(size 1.27 1.27)
				)
				(justify mirror)
			)
		)
		(duplicate_pad_numbers_are_jumpers no)
		(fp_poly
			(pts
				(xy -0.3048 -0.1016) (xy -0.3048 0.9906) (xy 0.3048 0.9906) (xy 0.3048 -0.1016)
			)
			(stroke
				(width 0)
				(type default)
			)
			(fill no)
			(layer "B.CrtYd")
		)
		(fp_line
			(start 0.3048 -0.1016)
			(end 0.3048 0.9906)
			(stroke
				(width 0.1)
				(type default)
			)
			(layer "B.Fab")
		)
		(fp_line
			(start -0.3048 -0.1016)
			(end 0.3048 -0.1016)
			(stroke
				(width 0.1)
				(type default)
			)
			(layer "B.Fab")
		)
		(fp_line
			(start 0.3048 0.9906)
			(end -0.3048 0.9906)
			(stroke
				(width 0.1)
				(type default)
			)
			(layer "B.Fab")
		)
		(fp_line
			(start -0.3048 0.9906)
			(end -0.3048 -0.1016)
			(stroke
				(width 0.1)
				(type default)
			)
			(layer "B.Fab")
		)
		(pad "1" smd rect
			(at 0 0 270)
			(size 0.508 0.508)
			(layers "B.Cu" "B.Mask" "B.Paste")
			(net "VCC_D_3V3")
		)
		(pad "2" smd rect
			(at 0 0.889 270)
			(size 0.508 0.508)
			(layers "B.Cu" "B.Mask" "B.Paste")
			(net "GND")
		)
		(zone
			(layer "B.Cu")
			(hatch none 0.5)
			(connect_pads
				(clearance 0)
			)
			(min_thickness 0.25)
			(keepout
				(tracks allowed)
				(vias not_allowed)
				(pads allowed)
				(copperpour not_allowed)
				(footprints allowed)
			)
			(placement
				(enabled no)
				(sheetname "")
			)
			(fill
				(thermal_gap 0.5)
				(thermal_bridge_width 0.5)
				(island_removal_mode 0)
			)
			(polygon
				(pts
					(xy 411.7848 -36.8046) (xy 411.7848 -36.2966) (xy 412.1658 -36.2966) (xy 412.1658 -36.8046)
				)
			)
		)
		(zone
			(layer "B.Cu")
			(hatch none 0.5)
			(connect_pads
				(clearance 0)
			)
			(min_thickness 0.25)
			(keepout
				(tracks not_allowed)
				(vias allowed)
				(pads allowed)
				(copperpour not_allowed)
				(footprints allowed)
			)
			(placement
				(enabled no)
				(sheetname "")
			)
			(fill
				(thermal_gap 0.5)
				(thermal_bridge_width 0.5)
				(island_removal_mode 0)
			)
			(polygon
				(pts
					(xy 412.1658 -36.8046) (xy 412.1658 -36.2966) (xy 411.7848 -36.2966) (xy 411.7848 -36.8046)
				)
			)
		)
	)
	(footprint ""
		(layer "B.Cu")
		(at 490.15396 -150.18004 -90)
		(property "Reference" "R1L22"
			(at 0 0 90)
			(layer "B.SilkS")
			(hide yes)
			(effects
				(font
					(size 1.27 1.27)
				)
				(justify mirror)
			)
		)
		(property "Value" ""
			(at 0 0 90)
			(layer "B.Fab")
			(effects
				(font
					(size 1.27 1.27)
				)
				(justify mirror)
			)
		)
		(duplicate_pad_numbers_are_jumpers no)
		(fp_poly
			(pts
				(xy 0.2794 -0.1016) (xy -0.2794 -0.1016) (xy -0.2794 0.9906) (xy 0.2794 0.9906)
			)
			(stroke
				(width 0)
				(type default)
			)
			(fill no)
			(layer "B.CrtYd")
		)
		(fp_line
			(start -0.2794 0.9906)
			(end -0.2794 -0.1016)
			(stroke
				(width 0.1)
				(type default)
			)
			(layer "B.Fab")
		)
		(fp_line
			(start 0.2794 0.9906)
			(end -0.2794 0.9906)
			(stroke
				(width 0.1)
				(type default)
			)
			(layer "B.Fab")
		)
		(fp_line
			(start -0.2794 -0.1016)
			(end 0.2794 -0.1016)
			(stroke
				(width 0.1)
				(type default)
			)
			(layer "B.Fab")
		)
		(fp_line
			(start 0.2794 -0.1016)
			(end 0.2794 0.9906)
			(stroke
				(width 0.1)
				(type default)
			)
			(layer "B.Fab")
		)
		(pad "1" smd rect
			(at 0 0 90)
			(size 0.508 0.508)
			(layers "B.Cu" "B.Mask" "B.Paste")
			(net "FM_DEBUG_RST_BTN_N")
		)
		(pad "2" smd rect
			(at 0 0.889 90)
			(size 0.508 0.508)
			(layers "B.Cu" "B.Mask" "B.Paste")
			(net "FP_RST_BTN_R_N")
		)
		(zone
			(layer "B.Cu")
			(hatch none 0.5)
			(connect_pads
				(clearance 0)
			)
			(min_thickness 0.25)
			(keepout
				(tracks not_allowed)
				(vias allowed)
				(pads allowed)
				(copperpour not_allowed)
				(footprints allowed)
			)
			(placement
				(enabled no)
				(sheetname "")
			)
			(fill
				(thermal_gap 0.5)
				(thermal_bridge_width 0.5)
				(island_removal_mode 0)
			)
			(polygon
				(pts
					(xy 489.51896 -149.92604) (xy 489.51896 -150.43404) (xy 489.89996 -150.43404) (xy 489.89996 -149.92604)
				)
			)
		)
		(zone
			(layer "B.Cu")
			(hatch none 0.5)
			(connect_pads
				(clearance 0)
			)
			(min_thickness 0.25)
			(keepout
				(tracks allowed)
				(vias not_allowed)
				(pads allowed)
				(copperpour not_allowed)
				(footprints allowed)
			)
			(placement
				(enabled no)
				(sheetname "")
			)
			(fill
				(thermal_gap 0.5)
				(thermal_bridge_width 0.5)
				(island_removal_mode 0)
			)
			(polygon
				(pts
					(xy 489.89996 -149.92604) (xy 489.89996 -150.43404) (xy 489.51896 -150.43404) (xy 489.51896 -149.92604)
				)
			)
		)
	)
	(footprint ""
		(layer "B.Cu")
		(at 195.2244 -96.5708 90)
		(property "Reference" "CT58"
			(at 0.8382 -0.84963 90)
			(unlocked yes)
			(layer "B.SilkS")
			(effects
				(font
					(size 0.7874 0.5842)
					(thickness 0.1524)
				)
				(justify left mirror)
			)
		)
		(property "Value" ""
			(at 0 0 90)
			(layer "B.Fab")
			(effects
				(font
					(size 1.27 1.27)
				)
				(justify mirror)
			)
		)
		(duplicate_pad_numbers_are_jumpers no)
		(fp_poly
			(pts
				(xy -0.3048 -0.1016) (xy -0.3048 0.9906) (xy 0.3048 0.9906) (xy 0.3048 -0.1016)
			)
			(stroke
				(width 0)
				(type default)
			)
			(fill no)
			(layer "B.CrtYd")
		)
		(fp_line
			(start 0.3048 -0.1016)
			(end 0.3048 0.9906)
			(stroke
				(width 0.1)
				(type default)
			)
			(layer "B.Fab")
		)
		(fp_line
			(start -0.3048 -0.1016)
			(end 0.3048 -0.1016)
			(stroke
				(width 0.1)
				(type default)
			)
			(layer "B.Fab")
		)
		(fp_line
			(start 0.3048 0.9906)
			(end -0.3048 0.9906)
			(stroke
				(width 0.1)
				(type default)
			)
			(layer "B.Fab")
		)
		(fp_line
			(start -0.3048 0.9906)
			(end -0.3048 -0.1016)
			(stroke
				(width 0.1)
				(type default)
			)
			(layer "B.Fab")
		)
		(pad "1" smd rect
			(at 0 0 270)
			(size 0.508 0.508)
			(layers "B.Cu" "B.Mask" "B.Paste")
			(net "A_TSENSE_PVSA_CPU0")
		)
		(pad "2" smd rect
			(at 0 0.889 270)
			(size 0.508 0.508)
			(layers "B.Cu" "B.Mask" "B.Paste")
			(net "GND")
		)
		(zone
			(layer "B.Cu")
			(hatch none 0.5)
			(connect_pads
				(clearance 0)
			)
			(min_thickness 0.25)
			(keepout
				(tracks allowed)
				(vias not_allowed)
				(pads allowed)
				(copperpour not_allowed)
				(footprints allowed)
			)
			(placement
				(enabled no)
				(sheetname "")
			)
			(fill
				(thermal_gap 0.5)
				(thermal_bridge_width 0.5)
				(island_removal_mode 0)
			)
			(polygon
				(pts
					(xy 195.4784 -96.8248) (xy 195.4784 -96.3168) (xy 195.8594 -96.3168) (xy 195.8594 -96.8248)
				)
			)
		)
		(zone
			(layer "B.Cu")
			(hatch none 0.5)
			(connect_pads
				(clearance 0)
			)
			(min_thickness 0.25)
			(keepout
				(tracks not_allowed)
				(vias allowed)
				(pads allowed)
				(copperpour not_allowed)
				(footprints allowed)
			)
			(placement
				(enabled no)
				(sheetname "")
			)
			(fill
				(thermal_gap 0.5)
				(thermal_bridge_width 0.5)
				(island_removal_mode 0)
			)
			(polygon
				(pts
					(xy 195.8594 -96.8248) (xy 195.8594 -96.3168) (xy 195.4784 -96.3168) (xy 195.4784 -96.8248)
				)
			)
		)
	)
)
